(kicad_pcb
	(version 20260206)
	(generator "pcbnew")
	(generator_version "10.0")
	(general
		(thickness 1.6)
		(legacy_teardrops no)
	)
	(paper "A4")
	(title_block
		(title "03242023_DA0F0TMBIJ0_F0T_Motherboard_J_brd_V01_OCP.brd")
		(comment 1 "Grand Teton / footprints 5022-5027 of 6105")
	)
	(layers
		(0 "F.Cu" signal "TOP")
		(4 "In1.Cu" signal "GND")
		(6 "In2.Cu" signal "IN1")
		(8 "In3.Cu" signal "GND1")
		(10 "In4.Cu" signal "IN2")
		(12 "In5.Cu" signal "GND2")
		(14 "In6.Cu" signal "IN3")
		(16 "In7.Cu" signal "GND3")
		(18 "In8.Cu" signal "VCC")
		(20 "In9.Cu" signal "VCC1")
		(22 "In10.Cu" signal "GND4")
		(24 "In11.Cu" signal "IN4")
		(26 "In12.Cu" signal "GND5")
		(28 "In13.Cu" signal "IN5")
		(30 "In14.Cu" signal "GND6")
		(32 "In15.Cu" signal "IN6")
		(34 "In16.Cu" signal "GND7")
		(2 "B.Cu" signal "BOTTOM")
		(9 "F.Adhes" user "F.Adhesive")
		(11 "B.Adhes" user "B.Adhesive")
		(13 "F.Paste" user "Package Geometry/Pastemask Top")
		(15 "B.Paste" user "Package Geometry/Pastemask Bottom")
		(5 "F.SilkS" user "Ref Des/Silkscreen Top")
		(7 "B.SilkS" user "Ref Des/Silkscreen Bottom")
		(1 "F.Mask" user "Board Geometry/Soldermask Top")
		(3 "B.Mask" user "Board Geometry/Soldermask Bottom")
		(17 "Dwgs.User" user "User.Drawings")
		(19 "Cmts.User" user "User.Comments")
		(21 "Eco1.User" user "User.Eco1")
		(23 "Eco2.User" user "User.Eco2")
		(25 "Edge.Cuts" user "Board Geometry/Outline")
		(27 "Margin" user)
		(31 "F.CrtYd" user "Package Geometry/Place Bound Top")
		(29 "B.CrtYd" user "Package Geometry/Place Bound Bottom")
		(35 "F.Fab" user "Ref Des/Assembly Top")
		(33 "B.Fab" user "Ref Des/Assembly Bottom")
	)
	(footprint ""
		(layer "B.Cu")
		(at 331.155294 -333.896208 -90)
		(property "Reference" "PC243_P0_7"
			(at 0 0 90)
			(layer "B.SilkS")
			(hide yes)
			(effects
				(font
					(size 1.27 1.27)
				)
				(justify mirror)
			)
		)
		(property "Value" ""
			(at 0 0 90)
			(layer "B.Fab")
			(effects
				(font
					(size 1.27 1.27)
				)
				(justify mirror)
			)
		)
		(duplicate_pad_numbers_are_jumpers no)
		(fp_line
			(start -0.7874 0.4064)
			(end 0.7874 0.4064)
			(stroke
				(width 0.1524)
				(type default)
			)
			(layer "B.SilkS")
		)
		(fp_line
			(start 0.7874 0.4064)
			(end 0.7874 -0.4064)
			(stroke
				(width 0.1524)
				(type default)
			)
			(layer "B.SilkS")
		)
		(fp_line
			(start -0.7874 -0.4064)
			(end -0.7874 0.4064)
			(stroke
				(width 0.1524)
				(type default)
			)
			(layer "B.SilkS")
		)
		(fp_line
			(start 0.7874 -0.4064)
			(end -0.7874 -0.4064)
			(stroke
				(width 0.1524)
				(type default)
			)
			(layer "B.SilkS")
		)
		(fp_line
			(start -0.67945 0.3048)
			(end -0.120396 0.3048)
			(stroke
				(width 0.1)
				(type default)
			)
			(layer "B.Fab")
		)
		(fp_line
			(start -0.120396 0.3048)
			(end -0.120396 0.2794)
			(stroke
				(width 0.1)
				(type default)
			)
			(layer "B.Fab")
		)
		(fp_line
			(start 0.12065 0.3048)
			(end 0.67945 0.3048)
			(stroke
				(width 0.1)
				(type default)
			)
			(layer "B.Fab")
		)
		(fp_line
			(start 0.67945 0.3048)
			(end 0.67945 -0.305054)
			(stroke
				(width 0.1)
				(type default)
			)
			(layer "B.Fab")
		)
		(fp_line
			(start -0.120396 0.2794)
			(end 0.12065 0.2794)
			(stroke
				(width 0.1)
				(type default)
			)
			(layer "B.Fab")
		)
		(fp_line
			(start 0.12065 0.2794)
			(end 0.12065 0.3048)
			(stroke
				(width 0.1)
				(type default)
			)
			(layer "B.Fab")
		)
		(fp_line
			(start -0.12065 -0.2794)
			(end -0.12065 -0.3048)
			(stroke
				(width 0.1)
				(type default)
			)
			(layer "B.Fab")
		)
		(fp_line
			(start 0.12065 -0.2794)
			(end -0.12065 -0.2794)
			(stroke
				(width 0.1)
				(type default)
			)
			(layer "B.Fab")
		)
		(fp_line
			(start -0.67945 -0.3048)
			(end -0.67945 0.3048)
			(stroke
				(width 0.1)
				(type default)
			)
			(layer "B.Fab")
		)
		(fp_line
			(start -0.12065 -0.3048)
			(end -0.67945 -0.3048)
			(stroke
				(width 0.1)
				(type default)
			)
			(layer "B.Fab")
		)
		(fp_line
			(start 0.12065 -0.305054)
			(end 0.12065 -0.2794)
			(stroke
				(width 0.1)
				(type default)
			)
			(layer "B.Fab")
		)
		(fp_line
			(start 0.67945 -0.305054)
			(end 0.12065 -0.305054)
			(stroke
				(width 0.1)
				(type default)
			)
			(layer "B.Fab")
		)
		(pad "1" smd circle
			(at 0.40005 0 90)
			(size 0 0)
			(layers "B.Cu" "B.Mask" "B.Paste")
			(net "PVCCIN_CPU0")
		)
		(pad "2" smd circle
			(at -0.40005 0 90)
			(size 0 0)
			(layers "B.Cu" "B.Mask" "B.Paste")
			(net "GND")
		)
	)
	(footprint ""
		(layer "B.Cu")
		(at 178.1556 -114.17554 -90)
		(property "Reference" "C1916"
			(at 0 0 90)
			(layer "B.SilkS")
			(hide yes)
			(effects
				(font
					(size 1.27 1.27)
				)
				(justify mirror)
			)
		)
		(property "Value" ""
			(at 0 0 90)
			(layer "B.Fab")
			(effects
				(font
					(size 1.27 1.27)
				)
				(justify mirror)
			)
		)
		(duplicate_pad_numbers_are_jumpers no)
		(fp_line
			(start -0.69215 0.2921)
			(end 0.69215 0.2921)
			(stroke
				(width 0.1524)
				(type default)
			)
			(layer "B.SilkS")
		)
		(fp_line
			(start 0.69215 0.2921)
			(end 0.69215 -0.2921)
			(stroke
				(width 0.1524)
				(type default)
			)
			(layer "B.SilkS")
		)
		(fp_line
			(start -0.69215 -0.2921)
			(end -0.69215 0.2921)
			(stroke
				(width 0.1524)
				(type default)
			)
			(layer "B.SilkS")
		)
		(fp_line
			(start 0.69215 -0.2921)
			(end -0.69215 -0.2921)
			(stroke
				(width 0.1524)
				(type default)
			)
			(layer "B.SilkS")
		)
		(fp_line
			(start -0.51435 0.2794)
			(end 0.51435 0.2794)
			(stroke
				(width 0.1)
				(type default)
			)
			(layer "B.Fab")
		)
		(fp_line
			(start 0.51435 0.2794)
			(end 0.51435 -0.2794)
			(stroke
				(width 0.1)
				(type default)
			)
			(layer "B.Fab")
		)
		(fp_line
			(start -0.51435 -0.2794)
			(end -0.51435 0.2794)
			(stroke
				(width 0.1)
				(type default)
			)
			(layer "B.Fab")
		)
		(fp_line
			(start 0.51435 -0.2794)
			(end -0.51435 -0.2794)
			(stroke
				(width 0.1)
				(type default)
			)
			(layer "B.Fab")
		)
		(pad "1" smd circle
			(at 0.40005 0 90)
			(size 0 0)
			(layers "B.Cu" "B.Mask" "B.Paste")
			(net "VCC_PLD_CORE")
		)
		(pad "2" smd circle
			(at -0.40005 0 90)
			(size 0 0)
			(layers "B.Cu" "B.Mask" "B.Paste")
			(net "GND")
		)
		(zone
			(layer "B.Cu")
			(hatch none 0.5)
			(connect_pads
				(clearance 0)
			)
			(min_thickness 0.25)
			(keepout
				(tracks not_allowed)
				(vias allowed)
				(pads allowed)
				(copperpour not_allowed)
				(footprints allowed)
			)
			(placement
				(enabled no)
				(sheetname "")
			)
			(fill
				(thermal_gap 0.5)
				(thermal_bridge_width 0.5)
				(island_removal_mode 0)
			)
			(polygon
				(pts
					(xy 178.06797 -113.98504) (xy 178.009804 -114.07648) (xy 178.009804 -114.27587) (xy 178.06797 -114.36604)
					(xy 178.24323 -114.36604) (xy 178.30165 -114.27587) (xy 178.30165 -114.07648) (xy 178.243484 -113.98504)
				)
			)
		)
	)
	(footprint ""
		(layer "B.Cu")
		(at 140.6779 -28.429458 90)
		(property "Reference" "U312"
			(at 2.765298 5.54609 0)
			(unlocked yes)
			(layer "B.SilkS")
			(effects
				(font
					(size 0.7874 0.5842)
					(thickness 0.1524)
				)
				(justify left mirror)
			)
		)
		(property "Value" ""
			(at 0 0 90)
			(layer "B.Fab")
			(effects
				(font
					(size 1.27 1.27)
				)
				(justify mirror)
			)
		)
		(duplicate_pad_numbers_are_jumpers no)
		(fp_line
			(start 1.2446 -1.2446)
			(end 1.2446 -0.4318)
			(stroke
				(width 0.1524)
				(type default)
			)
			(layer "B.SilkS")
		)
		(fp_line
			(start -1.2446 -1.2446)
			(end 1.2446 -1.2446)
			(stroke
				(width 0.1524)
				(type default)
			)
			(layer "B.SilkS")
		)
		(fp_line
			(start -1.2446 -0.56896)
			(end -1.2446 -1.2446)
			(stroke
				(width 0.1524)
				(type default)
			)
			(layer "B.SilkS")
		)
		(fp_line
			(start 1.2446 0.54356)
			(end 1.2446 1.2446)
			(stroke
				(width 0.1524)
				(type default)
			)
			(layer "B.SilkS")
		)
		(fp_line
			(start 1.2446 1.2446)
			(end -1.2446 1.2446)
			(stroke
				(width 0.1524)
				(type default)
			)
			(layer "B.SilkS")
		)
		(fp_line
			(start -1.2446 1.2446)
			(end -1.2446 0.54864)
			(stroke
				(width 0.1524)
				(type default)
			)
			(layer "B.SilkS")
		)
		(fp_poly
			(pts
				(xy 1.377442 -0.400304) (xy 1.649476 -1.21666) (xy 2.193544 -0.672592)
			)
			(stroke
				(width 0)
				(type default)
			)
			(fill yes)
			(layer "B.SilkS")
		)
		(fp_line
			(start 0.824992 -0.824992)
			(end 0.824992 0.824992)
			(stroke
				(width 0.1)
				(type default)
			)
			(layer "B.Fab")
		)
		(fp_line
			(start -0.824992 -0.824992)
			(end 0.824992 -0.824992)
			(stroke
				(width 0.1)
				(type default)
			)
			(layer "B.Fab")
		)
		(fp_line
			(start 0.824992 0.824992)
			(end -0.824992 0.824992)
			(stroke
				(width 0.1)
				(type default)
			)
			(layer "B.Fab")
		)
		(fp_line
			(start -0.824992 0.824992)
			(end -0.824992 -0.824992)
			(stroke
				(width 0.1)
				(type default)
			)
			(layer "B.Fab")
		)
		(fp_poly
			(pts
				(xy 1.389634 -0.199898) (xy 2.159 0.184658) (xy 2.159 -0.584708)
			)
			(stroke
				(width 0)
				(type default)
			)
			(fill yes)
			(layer "B.Fab")
		)
		(pad "1" smd rect
			(at 0.700024 -0.199898)
			(size 0.1778 0.8128)
			(layers "B.Cu" "B.Mask" "B.Paste")
			(net "USB2_HUB_2_BUF_EXT_R_DN")
		)
		(pad "2" smd rect
			(at 0.700024 0.199898)
			(size 0.1778 0.8128)
			(layers "B.Cu" "B.Mask" "B.Paste")
			(net "USB2_HUB_2_BUF_EXT_R_DP")
		)
		(pad "3" smd rect
			(at 0.599948 0.8001 270)
			(size 0.1778 0.6096)
			(layers "B.Cu" "B.Mask" "B.Paste")
			(net "TP_USB_HUB_2_TEST")
		)
		(pad "4" smd rect
			(at 0.199898 0.8001 270)
			(size 0.1778 0.6096)
			(layers "B.Cu" "B.Mask" "B.Paste")
			(net "TP_USB_HUB_2_CD")
		)
		(pad "5" smd rect
			(at -0.199898 0.8001 270)
			(size 0.1778 0.6096)
			(layers "B.Cu" "B.Mask" "B.Paste")
			(net "PD_USB_HUB_2_RSTN")
		)
		(pad "6" smd rect
			(at -0.599948 0.8001 270)
			(size 0.1778 0.6096)
			(layers "B.Cu" "B.Mask" "B.Paste")
			(net "PD_USB_HUB_2_EQ")
		)
		(pad "7" smd rect
			(at -0.700024 0.199898)
			(size 0.1778 0.8128)
			(layers "B.Cu" "B.Mask" "B.Paste")
			(net "USB2_HUB_2_BUF_EXT_R_DP")
		)
		(pad "8" smd rect
			(at -0.700024 -0.199898)
			(size 0.1778 0.8128)
			(layers "B.Cu" "B.Mask" "B.Paste")
			(net "USB2_HUB_2_BUF_EXT_R_DN")
		)
		(pad "9" smd rect
			(at -0.599948 -0.8001 270)
			(size 0.1778 0.6096)
			(layers "B.Cu" "B.Mask" "B.Paste")
			(net "TP_USB_HUB_2_ENA_HS")
		)
		(pad "10" smd rect
			(at -0.199898 -0.8001 270)
			(size 0.1778 0.6096)
			(layers "B.Cu" "B.Mask" "B.Paste")
			(net "GND")
		)
		(pad "11" smd rect
			(at 0.199898 -0.8001 270)
			(size 0.1778 0.6096)
			(layers "B.Cu" "B.Mask" "B.Paste")
			(net "PD_USB_HUB_2_VREG")
		)
		(pad "12" smd rect
			(at 0.599948 -0.8001 270)
			(size 0.1778 0.6096)
			(layers "B.Cu" "B.Mask" "B.Paste")
			(net "P3V3_AUX")
		)
	)
	(footprint ""
		(layer "B.Cu")
		(at 179.506626 -417.030154 180)
		(property "Reference" "R2801"
			(at 0 0 0)
			(layer "B.SilkS")
			(hide yes)
			(effects
				(font
					(size 1.27 1.27)
				)
				(justify mirror)
			)
		)
		(property "Value" ""
			(at 0 0 0)
			(layer "B.Fab")
			(effects
				(font
					(size 1.27 1.27)
				)
				(justify mirror)
			)
		)
		(duplicate_pad_numbers_are_jumpers no)
		(fp_line
			(start 0.7874 0.4064)
			(end 0.7874 -0.4064)
			(stroke
				(width 0.1524)
				(type default)
			)
			(layer "B.SilkS")
		)
		(fp_line
			(start 0.7874 -0.4064)
			(end -0.7874 -0.4064)
			(stroke
				(width 0.1524)
				(type default)
			)
			(layer "B.SilkS")
		)
		(fp_line
			(start -0.7874 0.4064)
			(end 0.7874 0.4064)
			(stroke
				(width 0.1524)
				(type default)
			)
			(layer "B.SilkS")
		)
		(fp_line
			(start -0.7874 -0.4064)
			(end -0.7874 0.4064)
			(stroke
				(width 0.1524)
				(type default)
			)
			(layer "B.SilkS")
		)
		(fp_line
			(start 0.67945 0.3048)
			(end 0.67945 -0.305054)
			(stroke
				(width 0.1)
				(type default)
			)
			(layer "B.Fab")
		)
		(fp_line
			(start 0.67945 -0.305054)
			(end 0.12065 -0.305054)
			(stroke
				(width 0.1)
				(type default)
			)
			(layer "B.Fab")
		)
		(fp_line
			(start 0.12065 0.3048)
			(end 0.67945 0.3048)
			(stroke
				(width 0.1)
				(type default)
			)
			(layer "B.Fab")
		)
		(fp_line
			(start 0.12065 0.2794)
			(end 0.12065 0.3048)
			(stroke
				(width 0.1)
				(type default)
			)
			(layer "B.Fab")
		)
		(fp_line
			(start 0.12065 -0.2794)
			(end -0.12065 -0.2794)
			(stroke
				(width 0.1)
				(type default)
			)
			(layer "B.Fab")
		)
		(fp_line
			(start 0.12065 -0.305054)
			(end 0.12065 -0.2794)
			(stroke
				(width 0.1)
				(type default)
			)
			(layer "B.Fab")
		)
		(fp_line
			(start -0.120396 0.3048)
			(end -0.120396 0.2794)
			(stroke
				(width 0.1)
				(type default)
			)
			(layer "B.Fab")
		)
		(fp_line
			(start -0.120396 0.2794)
			(end 0.12065 0.2794)
			(stroke
				(width 0.1)
				(type default)
			)
			(layer "B.Fab")
		)
		(fp_line
			(start -0.12065 -0.2794)
			(end -0.12065 -0.3048)
			(stroke
				(width 0.1)
				(type default)
			)
			(layer "B.Fab")
		)
		(fp_line
			(start -0.12065 -0.3048)
			(end -0.67945 -0.3048)
			(stroke
				(width 0.1)
				(type default)
			)
			(layer "B.Fab")
		)
		(fp_line
			(start -0.67945 0.3048)
			(end -0.120396 0.3048)
			(stroke
				(width 0.1)
				(type default)
			)
			(layer "B.Fab")
		)
		(fp_line
			(start -0.67945 -0.3048)
			(end -0.67945 0.3048)
			(stroke
				(width 0.1)
				(type default)
			)
			(layer "B.Fab")
		)
		(pad "1" smd circle
			(at 0.40005 0)
			(size 0 0)
			(layers "B.Cu" "B.Mask" "B.Paste")
			(net "SMB_FAN_3V3AUX_R_SDA")
		)
		(pad "2" smd circle
			(at -0.40005 0)
			(size 0 0)
			(layers "B.Cu" "B.Mask" "B.Paste")
			(net "SMB_FAN_3V3AUX_BUF_SDA")
		)
	)
	(footprint ""
		(layer "B.Cu")
		(at 346.026486 -54.487826 90)
		(property "Reference" "C1252"
			(at 0 0 90)
			(layer "B.SilkS")
			(hide yes)
			(effects
				(font
					(size 1.27 1.27)
				)
				(justify mirror)
			)
		)
		(property "Value" ""
			(at 0 0 90)
			(layer "B.Fab")
			(effects
				(font
					(size 1.27 1.27)
				)
				(justify mirror)
			)
		)
		(duplicate_pad_numbers_are_jumpers no)
		(fp_line
			(start 1.125982 -0.5842)
			(end -1.2954 -0.5842)
			(stroke
				(width 0.1524)
				(type default)
			)
			(layer "B.SilkS")
		)
		(fp_line
			(start 0 -0.5842)
			(end 0 0.5842)
			(stroke
				(width 0.1524)
				(type default)
			)
			(layer "B.SilkS")
		)
		(fp_line
			(start -1.2954 -0.5842)
			(end -1.2954 0.5842)
			(stroke
				(width 0.1524)
				(type default)
			)
			(layer "B.SilkS")
		)
		(fp_line
			(start 1.2954 0.5842)
			(end 1.2954 -0.350266)
			(stroke
				(width 0.1524)
				(type default)
			)
			(layer "B.SilkS")
		)
		(fp_line
			(start -1.2954 0.5842)
			(end 1.2954 0.5842)
			(stroke
				(width 0.1524)
				(type default)
			)
			(layer "B.SilkS")
		)
		(fp_line
			(start 0.8636 -0.4572)
			(end -0.8636 -0.4572)
			(stroke
				(width 0.1)
				(type default)
			)
			(layer "B.Fab")
		)
		(fp_line
			(start -0.8636 -0.4572)
			(end -0.8636 -0.4064)
			(stroke
				(width 0.1)
				(type default)
			)
			(layer "B.Fab")
		)
		(fp_line
			(start 1.1938 -0.4064)
			(end 0.8636 -0.4064)
			(stroke
				(width 0.1)
				(type default)
			)
			(layer "B.Fab")
		)
		(fp_line
			(start 0.8636 -0.4064)
			(end 0.8636 -0.4572)
			(stroke
				(width 0.1)
				(type default)
			)
			(layer "B.Fab")
		)
		(fp_line
			(start -0.8636 -0.4064)
			(end -1.1938 -0.4064)
			(stroke
				(width 0.1)
				(type default)
			)
			(layer "B.Fab")
		)
		(fp_line
			(start -1.1938 -0.4064)
			(end -1.1938 0.4064)
			(stroke
				(width 0.1)
				(type default)
			)
			(layer "B.Fab")
		)
		(fp_line
			(start 1.1938 0.4064)
			(end 1.1938 -0.4064)
			(stroke
				(width 0.1)
				(type default)
			)
			(layer "B.Fab")
		)
		(fp_line
			(start 0.8636 0.4064)
			(end 1.1938 0.4064)
			(stroke
				(width 0.1)
				(type default)
			)
			(layer "B.Fab")
		)
		(fp_line
			(start -0.8636 0.4064)
			(end -0.8636 0.4572)
			(stroke
				(width 0.1)
				(type default)
			)
			(layer "B.Fab")
		)
		(fp_line
			(start -1.1938 0.4064)
			(end -0.8636 0.4064)
			(stroke
				(width 0.1)
				(type default)
			)
			(layer "B.Fab")
		)
		(fp_line
			(start 0.8636 0.4572)
			(end 0.8636 0.4064)
			(stroke
				(width 0.1)
				(type default)
			)
			(layer "B.Fab")
		)
		(fp_line
			(start -0.8636 0.4572)
			(end 0.8636 0.4572)
			(stroke
				(width 0.1)
				(type default)
			)
			(layer "B.Fab")
		)
		(pad "1" smd rect
			(at 0.7366 0)
			(size 0.7112 0.8128)
			(layers "B.Cu" "B.Mask" "B.Paste")
			(net "P1V8_PCH_PLL_AUX")
		)
		(pad "2" smd rect
			(at -0.7366 0)
			(size 0.7112 0.8128)
			(layers "B.Cu" "B.Mask" "B.Paste")
			(net "GND")
		)
	)
	(footprint ""
		(layer "B.Cu")
		(at 118.18112 -255.8542 -90)
		(property "Reference" "C332"
			(at 0 0 90)
			(layer "B.SilkS")
			(hide yes)
			(effects
				(font
					(size 1.27 1.27)
				)
				(justify mirror)
			)
		)
		(property "Value" ""
			(at 0 0 90)
			(layer "B.Fab")
			(effects
				(font
					(size 1.27 1.27)
				)
				(justify mirror)
			)
		)
		(duplicate_pad_numbers_are_jumpers no)
		(fp_line
			(start -1.524 0.762)
			(end 1.524 0.762)
			(stroke
				(width 0.1524)
				(type default)
			)
			(layer "B.SilkS")
		)
		(fp_line
			(start 1.524 0.762)
			(end 1.524 -0.762)
			(stroke
				(width 0.1524)
				(type default)
			)
			(layer "B.SilkS")
		)
		(fp_line
			(start -1.524 -0.762)
			(end -1.524 0.762)
			(stroke
				(width 0.1524)
				(type default)
			)
			(layer "B.SilkS")
		)
		(fp_line
			(start 1.524 -0.762)
			(end -1.524 -0.762)
			(stroke
				(width 0.1524)
				(type default)
			)
			(layer "B.SilkS")
		)
		(fp_line
			(start -1.1049 0.724916)
			(end -1.1049 -0.724916)
			(stroke
				(width 0.1)
				(type default)
			)
			(layer "B.Fab")
		)
		(fp_line
			(start 1.1049 0.724916)
			(end -1.1049 0.724916)
			(stroke
				(width 0.1)
				(type default)
			)
			(layer "B.Fab")
		)
		(fp_line
			(start -1.1049 -0.724916)
			(end 1.1049 -0.724916)
			(stroke
				(width 0.1)
				(type default)
			)
			(layer "B.Fab")
		)
		(fp_line
			(start 1.1049 -0.724916)
			(end 1.1049 0.724916)
			(stroke
				(width 0.1)
				(type default)
			)
			(layer "B.Fab")
		)
		(pad "1" smd rect
			(at 0.889 0 270)
			(size 1.016 1.27)
			(layers "B.Cu" "B.Mask" "B.Paste")
			(net "PVCCIN_CPU1")
		)
		(pad "2" smd rect
			(at -0.889 0 270)
			(size 1.016 1.27)
			(layers "B.Cu" "B.Mask" "B.Paste")
			(net "GND")
		)
	)
)
